(kicad_pcb
	(version 20260206)
	(generator "pcbnew")
	(generator_version "10.0")
	(general
		(thickness 1.6)
		(legacy_teardrops no)
	)
	(paper "A4")
	(title_block
		(title "Bryce Canyon_IOM_IOC_16318-2_OCP.brd")
		(comment 1 "Bryce Canyon / footprints 797-803 of 1605")
	)
	(layers
		(0 "F.Cu" signal "TOP")
		(4 "In1.Cu" signal "L2GND")
		(6 "In2.Cu" signal "L3")
		(8 "In3.Cu" signal "L4VCC")
		(10 "In4.Cu" signal "L5VCC")
		(12 "In5.Cu" signal "L6")
		(14 "In6.Cu" signal "L7GND")
		(2 "B.Cu" signal "BOTTOM")
		(9 "F.Adhes" user "F.Adhesive")
		(11 "B.Adhes" user "B.Adhesive")
		(13 "F.Paste" user "Package Geometry/Pastemask Top")
		(15 "B.Paste" user "Package Geometry/Pastemask Bottom")
		(5 "F.SilkS" user "Ref Des/Silkscreen Top")
		(7 "B.SilkS" user "Ref Des/Silkscreen Bottom")
		(1 "F.Mask" user "Board Geometry/Soldermask Top")
		(3 "B.Mask" user "Board Geometry/Soldermask Bottom")
		(17 "Dwgs.User" user "User.Drawings")
		(19 "Cmts.User" user "User.Comments")
		(21 "Eco1.User" user "User.Eco1")
		(23 "Eco2.User" user "User.Eco2")
		(25 "Edge.Cuts" user "Board Geometry/Outline")
		(27 "Margin" user)
		(31 "F.CrtYd" user "Package Geometry/Place Bound Top")
		(29 "B.CrtYd" user "Package Geometry/Place Bound Bottom")
		(35 "F.Fab" user "Ref Des/Assembly Top")
		(33 "B.Fab" user "Ref Des/Assembly Bottom")
	)
	(footprint ""
		(layer "F.Cu")
		(at 36.068 -130.5052 180)
		(property "Reference" "R308"
			(at 0 0 180)
			(layer "F.SilkS")
			(hide yes)
			(effects
				(font
					(size 1.27 1.27)
				)
			)
		)
		(property "Value" "4K7R2F-GP"
			(at 0.064008 -3.993896 180)
			(unlocked yes)
			(layer "F.Fab")
			(hide yes)
			(effects
				(font
					(size 1.016 1.016)
					(thickness 0.1524)
				)
			)
		)
		(property "Device Type" "R402H16"
			(at 0.064008 -5.517896 180)
			(unlocked yes)
			(layer "F.Fab")
			(hide yes)
			(effects
				(font
					(size 1.016 1.016)
					(thickness 0.1524)
				)
			)
		)
		(duplicate_pad_numbers_are_jumpers no)
		(fp_line
			(start 0.508 -0.9398)
			(end -0.508 -0.9398)
			(stroke
				(width 0.1524)
				(type default)
			)
			(layer "F.SilkS")
		)
		(fp_line
			(start -0.508 -0.9398)
			(end -0.508 0.9398)
			(stroke
				(width 0.1524)
				(type default)
			)
			(layer "F.SilkS")
		)
		(fp_rect
			(start -0.508 0.9398)
			(end 0.508 -0.9398)
			(stroke
				(width 0)
				(type default)
			)
			(fill no)
			(layer "F.CrtYd")
		)
		(fp_rect
			(start -0.508 0.9398)
			(end 0.508 -0.9398)
			(stroke
				(width 0)
				(type default)
			)
			(fill no)
			(layer "F.Fab")
		)
		(pad "1" smd custom
			(at 0 -0.4445 180)
			(size 0.1397 0.1397)
			(layers "F.Cu" "F.Mask" "F.Paste")
			(net "P3V3_STBY")
			(options
				(clearance outline)
				(anchor circle)
			)
			(primitives
				(gr_poly
					(pts
						(arc
							(start -0.1778 -0.2794)
							(mid -0.249642 -0.249642)
							(end -0.2794 -0.1778)
						)
						(arc
							(start -0.2794 0.1778)
							(mid -0.249642 0.249642)
							(end -0.1778 0.2794)
						)
						(arc
							(start 0.1778 0.2794)
							(mid 0.249642 0.249642)
							(end 0.2794 0.1778)
						)
						(arc
							(start 0.2794 -0.1778)
							(mid 0.249642 -0.249642)
							(end 0.1778 -0.2794)
						)
					)
					(width 0)
					(fill yes)
				)
			)
		)
		(pad "2" smd custom
			(at 0 0.4445 180)
			(size 0.1397 0.1397)
			(layers "F.Cu" "F.Mask" "F.Paste")
			(net "OSC_OE")
			(options
				(clearance outline)
				(anchor circle)
			)
			(primitives
				(gr_poly
					(pts
						(arc
							(start -0.1778 -0.2794)
							(mid -0.249642 -0.249642)
							(end -0.2794 -0.1778)
						)
						(arc
							(start -0.2794 0.1778)
							(mid -0.249642 0.249642)
							(end -0.1778 0.2794)
						)
						(arc
							(start 0.1778 0.2794)
							(mid 0.249642 0.249642)
							(end 0.2794 0.1778)
						)
						(arc
							(start 0.2794 -0.1778)
							(mid 0.249642 -0.249642)
							(end 0.1778 -0.2794)
						)
					)
					(width 0)
					(fill yes)
				)
			)
		)
	)
	(footprint ""
		(layer "F.Cu")
		(at 75.3364 -133.2865 -90)
		(property "Reference" "C513"
			(at 0 0 270)
			(layer "F.SilkS")
			(hide yes)
			(effects
				(font
					(size 1.27 1.27)
				)
			)
		)
		(property "Value" "SCD1U16V2KX-3GP"
			(at 1.1811 -2.7051 270)
			(unlocked yes)
			(layer "F.Fab")
			(hide yes)
			(effects
				(font
					(size 1.016 1.016)
					(thickness 0.1524)
				)
			)
		)
		(property "Device Type" "C402H22"
			(at 1.1811 -4.2291 270)
			(unlocked yes)
			(layer "F.Fab")
			(hide yes)
			(effects
				(font
					(size 1.016 1.016)
					(thickness 0.1524)
				)
			)
		)
		(duplicate_pad_numbers_are_jumpers no)
		(fp_rect
			(start -0.4318 0.9525)
			(end 0.4318 -0.9525)
			(stroke
				(width 0)
				(type default)
			)
			(fill no)
			(layer "F.CrtYd")
		)
		(fp_rect
			(start -0.4318 0.9525)
			(end 0.4318 -0.9525)
			(stroke
				(width 0)
				(type default)
			)
			(fill no)
			(layer "F.Fab")
		)
		(pad "1" smd custom
			(at 0 -0.4445 270)
			(size 0.1524 0.1524)
			(layers "F.Cu" "F.Mask" "F.Paste")
			(net "P3V3_STBY")
			(options
				(clearance outline)
				(anchor circle)
			)
			(primitives
				(gr_poly
					(pts
						(arc
							(start 0.3048 -0.2032)
							(mid 0.275042 -0.275042)
							(end 0.2032 -0.3048)
						)
						(arc
							(start -0.2032 -0.3048)
							(mid -0.275042 -0.275042)
							(end -0.3048 -0.2032)
						)
						(arc
							(start -0.3048 0.2032)
							(mid -0.275042 0.275042)
							(end -0.2032 0.3048)
						)
						(arc
							(start 0.2032 0.3048)
							(mid 0.275042 0.275042)
							(end 0.3048 0.2032)
						)
					)
					(width 0)
					(fill yes)
				)
			)
		)
		(pad "2" smd custom
			(at 0 0.4445 270)
			(size 0.1524 0.1524)
			(layers "F.Cu" "F.Mask" "F.Paste")
			(net "GND")
			(options
				(clearance outline)
				(anchor circle)
			)
			(primitives
				(gr_poly
					(pts
						(arc
							(start 0.3048 -0.2032)
							(mid 0.275042 -0.275042)
							(end 0.2032 -0.3048)
						)
						(arc
							(start -0.2032 -0.3048)
							(mid -0.275042 -0.275042)
							(end -0.3048 -0.2032)
						)
						(arc
							(start -0.3048 0.2032)
							(mid -0.275042 0.275042)
							(end -0.2032 0.3048)
						)
						(arc
							(start 0.2032 0.3048)
							(mid 0.275042 0.275042)
							(end 0.3048 0.2032)
						)
					)
					(width 0)
					(fill yes)
				)
			)
		)
	)
	(footprint ""
		(layer "F.Cu")
		(at 214.63 -69.088 -45)
		(property "Reference" "VIA45"
			(at 0 0 315)
			(layer "F.SilkS")
			(hide yes)
			(effects
				(font
					(size 1.27 1.27)
				)
			)
		)
		(property "Value" "100OHM-8L-1D6MM-L18L16-GP"
			(at -3.721059 -4.508373 315)
			(unlocked yes)
			(layer "F.Fab")
			(hide yes)
			(effects
				(font
					(size 1.016 1.016)
					(thickness 0.1524)
				)
			)
		)
		(property "Device Type" "VIA-PCIE-4P-394076"
			(at -3.721059 -6.032502 315)
			(unlocked yes)
			(layer "F.Fab")
			(hide yes)
			(effects
				(font
					(size 1.016 1.016)
					(thickness 0.1524)
				)
			)
		)
		(duplicate_pad_numbers_are_jumpers no)
		(fp_poly
			(pts
				(xy -1.968472 -0.380877) (xy 1.968528 -0.380878) (xy 1.968527 0.381122) (xy -1.968472 0.381122)
			)
			(stroke
				(width 0)
				(type default)
			)
			(fill no)
			(layer "F.CrtYd")
		)
		(fp_poly
			(pts
				(xy -1.968472 -0.380877) (xy 1.968528 -0.380878) (xy 1.968527 0.381122) (xy -1.968472 0.381122)
			)
			(stroke
				(width 0)
				(type default)
			)
			(fill no)
			(layer "F.Fab")
		)
		(pad "1" thru_hole circle
			(at -1.5875 0 315)
			(size 0.508 0.508)
			(drill 0.254)
			(layers "*.Cu" "*.Mask")
			(remove_unused_layers no)
			(net "GND")
			(clearance 0.127)
			(thermal_gap 0.127)
		)
		(pad "2" thru_hole circle
			(at -0.571501 0 315)
			(size 0.508 0.508)
			(drill 0.254)
			(layers "*.Cu" "*.Mask")
			(remove_unused_layers no)
			(net "PHY_IOC_TO_CON_B_0_DP")
			(clearance 0.127)
			(thermal_gap 0.127)
		)
		(pad "3" thru_hole circle
			(at 0.571501 0 315)
			(size 0.508 0.508)
			(drill 0.254)
			(layers "*.Cu" "*.Mask")
			(remove_unused_layers no)
			(net "PHY_IOC_TO_CON_B_0_DN")
			(clearance 0.127)
			(thermal_gap 0.127)
		)
		(pad "4" thru_hole circle
			(at 1.5875 0 315)
			(size 0.508 0.508)
			(drill 0.254)
			(layers "*.Cu" "*.Mask")
			(remove_unused_layers no)
			(net "GND")
			(clearance 0.127)
			(thermal_gap 0.127)
		)
	)
	(footprint ""
		(layer "F.Cu")
		(at 81.65338 -178.453796 180)
		(property "Reference" "C192"
			(at 0 0 180)
			(layer "F.SilkS")
			(hide yes)
			(effects
				(font
					(size 1.27 1.27)
				)
			)
		)
		(property "Value" "SC10U6D3V5KX-4GP"
			(at -0.0762 -6.1214 180)
			(unlocked yes)
			(layer "F.Fab")
			(hide yes)
			(effects
				(font
					(size 1.016 1.016)
					(thickness 0.1524)
				)
			)
		)
		(property "Device Type" "C805H58"
			(at -0.0762 -8.1534 180)
			(unlocked yes)
			(layer "F.Fab")
			(hide yes)
			(effects
				(font
					(size 1.016 1.016)
					(thickness 0.1524)
				)
			)
		)
		(duplicate_pad_numbers_are_jumpers no)
		(fp_line
			(start 0.635 0)
			(end -0.635 0)
			(stroke
				(width 0.508)
				(type default)
			)
			(layer "F.SilkS")
		)
		(fp_rect
			(start -0.9652 1.778)
			(end 0.9652 -1.778)
			(stroke
				(width 0)
				(type default)
			)
			(fill no)
			(layer "F.CrtYd")
		)
		(fp_poly
			(pts
				(xy -0.9652 -1.778) (xy 0.9652 -1.778) (xy 0.9652 1.778) (xy -0.9652 1.778)
			)
			(stroke
				(width 0)
				(type default)
			)
			(fill no)
			(layer "F.Fab")
		)
		(pad "1" smd rect
			(at 0 -0.9652 180)
			(size 1.397 1.143)
			(layers "F.Cu" "F.Mask" "F.Paste")
			(net "TPS74801_P2V5_STBY_OUT")
		)
		(pad "2" smd rect
			(at 0 0.9652 180)
			(size 1.397 1.143)
			(layers "F.Cu" "F.Mask" "F.Paste")
			(net "GND")
		)
	)
	(footprint ""
		(layer "F.Cu")
		(at 206.000096 -6.199886)
		(property "Reference" "LED7"
			(at 0 0 0)
			(layer "F.SilkS")
			(hide yes)
			(effects
				(font
					(size 1.27 1.27)
				)
			)
		)
		(property "Value" "LED-BY-14-GP"
			(at -4.7752 -2.1844 0)
			(unlocked yes)
			(layer "F.Fab")
			(hide yes)
			(effects
				(font
					(size 1.016 1.016)
					(thickness 0.1524)
				)
			)
		)
		(property "Device Type" "LED-100-3PH206"
			(at -4.7752 -3.7084 0)
			(unlocked yes)
			(layer "F.Fab")
			(hide yes)
			(effects
				(font
					(size 1.016 1.016)
					(thickness 0.1524)
				)
			)
		)
		(duplicate_pad_numbers_are_jumpers no)
		(fp_line
			(start -3.7592 -1.524)
			(end 3.7592 -1.524)
			(stroke
				(width 0.1524)
				(type default)
			)
			(layer "F.SilkS")
		)
		(fp_line
			(start -3.7592 8.0264)
			(end -3.7592 -1.524)
			(stroke
				(width 0.1524)
				(type default)
			)
			(layer "F.SilkS")
		)
		(fp_line
			(start -1.75387 1.04394)
			(end -1.75387 3.63474)
			(stroke
				(width 0.1524)
				(type default)
			)
			(layer "F.SilkS")
		)
		(fp_line
			(start -1.75387 2.33934)
			(end -3.45567 2.33934)
			(stroke
				(width 0.1524)
				(type default)
			)
			(layer "F.SilkS")
		)
		(fp_line
			(start -1.75387 3.63474)
			(end -0.45847 2.33934)
			(stroke
				(width 0.1524)
				(type default)
			)
			(layer "F.SilkS")
		)
		(fp_line
			(start -0.45847 2.33934)
			(end -1.75387 1.04394)
			(stroke
				(width 0.1524)
				(type default)
			)
			(layer "F.SilkS")
		)
		(fp_line
			(start -0.45847 2.33934)
			(end 0.58293 2.33934)
			(stroke
				(width 0.1524)
				(type default)
			)
			(layer "F.SilkS")
		)
		(fp_line
			(start -0.45847 3.05054)
			(end -0.45847 1.42494)
			(stroke
				(width 0.1524)
				(type default)
			)
			(layer "F.SilkS")
		)
		(fp_line
			(start 0.58293 2.33934)
			(end 1.87833 1.04394)
			(stroke
				(width 0.1524)
				(type default)
			)
			(layer "F.SilkS")
		)
		(fp_line
			(start 0.58293 3.05054)
			(end 0.58293 1.42494)
			(stroke
				(width 0.1524)
				(type default)
			)
			(layer "F.SilkS")
		)
		(fp_line
			(start 1.87833 1.04394)
			(end 1.87833 3.63474)
			(stroke
				(width 0.1524)
				(type default)
			)
			(layer "F.SilkS")
		)
		(fp_line
			(start 1.87833 2.33934)
			(end 2.81813 2.33934)
			(stroke
				(width 0.1524)
				(type default)
			)
			(layer "F.SilkS")
		)
		(fp_line
			(start 1.87833 3.63474)
			(end 0.58293 2.33934)
			(stroke
				(width 0.1524)
				(type default)
			)
			(layer "F.SilkS")
		)
		(fp_line
			(start 3.7592 -1.524)
			(end 3.7592 8.0264)
			(stroke
				(width 0.1524)
				(type default)
			)
			(layer "F.SilkS")
		)
		(fp_line
			(start 3.7592 8.0264)
			(end -3.7592 8.0264)
			(stroke
				(width 0.1524)
				(type default)
			)
			(layer "F.SilkS")
		)
		(fp_circle
			(center -2.54 0)
			(end -1.5494 0)
			(stroke
				(width 0.3048)
				(type default)
			)
			(fill no)
			(layer "F.SilkS")
		)
		(fp_circle
			(center 0 0)
			(end 0.9906 0)
			(stroke
				(width 0.3048)
				(type default)
			)
			(fill no)
			(layer "F.SilkS")
		)
		(fp_circle
			(center 2.54 0)
			(end 3.5306 0)
			(stroke
				(width 0.3048)
				(type default)
			)
			(fill no)
			(layer "F.SilkS")
		)
		(fp_rect
			(start -3.5052 7.7724)
			(end 3.5052 -1.27)
			(stroke
				(width 0)
				(type default)
			)
			(fill no)
			(layer "F.CrtYd")
		)
		(fp_poly
			(pts
				(xy -4.0132 8.2804) (xy -4.0132 -1.778) (xy -3.5052 -1.778) (xy -3.5052 7.7724) (xy 3.5052 7.7724)
				(xy 3.5052 -1.27) (xy -3.50012 -1.27) (xy -3.50012 -1.778) (xy 4.0132 -1.778) (xy 4.0132 8.2804)
			)
			(stroke
				(width 0)
				(type default)
			)
			(fill no)
			(layer "F.CrtYd")
		)
		(fp_rect
			(start -4.0132 8.2804)
			(end 4.0132 -1.778)
			(stroke
				(width 0)
				(type default)
			)
			(fill no)
			(layer "F.Fab")
		)
		(pad "1" thru_hole circle
			(at -2.54 0)
			(size 1.27 1.27)
			(drill 0.889)
			(layers "*.Cu" "*.Mask")
			(remove_unused_layers no)
			(net "ML_PWR_BLUE_LED_R")
			(clearance 0.1651)
			(thermal_gap 0.1651)
		)
		(pad "2" thru_hole circle
			(at 0 0)
			(size 1.27 1.27)
			(drill 0.889)
			(layers "*.Cu" "*.Mask")
			(remove_unused_layers no)
			(net "GND")
			(clearance 0.1651)
			(thermal_gap 0.1651)
		)
		(pad "3" thru_hole circle
			(at 2.54 0)
			(size 1.27 1.27)
			(drill 0.889)
			(layers "*.Cu" "*.Mask")
			(remove_unused_layers no)
			(net "ML_PWR_YELLOW_LED_R")
			(clearance 0.1651)
			(thermal_gap 0.1651)
		)
	)
	(footprint ""
		(layer "F.Cu")
		(at 51.0159 -163.7538)
		(property "Reference" "R409"
			(at 0 0 0)
			(layer "F.SilkS")
			(hide yes)
			(effects
				(font
					(size 1.27 1.27)
				)
			)
		)
		(property "Value" "1K4R2F-1-GP"
			(at 0.064008 -3.993896 0)
			(unlocked yes)
			(layer "F.Fab")
			(hide yes)
			(effects
				(font
					(size 1.016 1.016)
					(thickness 0.1524)
				)
			)
		)
		(property "Device Type" "R402H16"
			(at 0.064008 -5.517896 0)
			(unlocked yes)
			(layer "F.Fab")
			(hide yes)
			(effects
				(font
					(size 1.016 1.016)
					(thickness 0.1524)
				)
			)
		)
		(duplicate_pad_numbers_are_jumpers no)
		(fp_line
			(start -0.508 -0.9398)
			(end -0.508 0.9398)
			(stroke
				(width 0.1524)
				(type default)
			)
			(layer "F.SilkS")
		)
		(fp_line
			(start 0.508 -0.9398)
			(end -0.508 -0.9398)
			(stroke
				(width 0.1524)
				(type default)
			)
			(layer "F.SilkS")
		)
		(fp_rect
			(start -0.508 0.9398)
			(end 0.508 -0.9398)
			(stroke
				(width 0)
				(type default)
			)
			(fill no)
			(layer "F.CrtYd")
		)
		(fp_rect
			(start -0.508 0.9398)
			(end 0.508 -0.9398)
			(stroke
				(width 0)
				(type default)
			)
			(fill no)
			(layer "F.Fab")
		)
		(pad "1" smd custom
			(at 0 -0.4445)
			(size 0.1397 0.1397)
			(layers "F.Cu" "F.Mask" "F.Paste")
			(net "P3V3")
			(options
				(clearance outline)
				(anchor circle)
			)
			(primitives
				(gr_poly
					(pts
						(arc
							(start -0.1778 -0.2794)
							(mid -0.249642 -0.249642)
							(end -0.2794 -0.1778)
						)
						(arc
							(start -0.2794 0.1778)
							(mid -0.249642 0.249642)
							(end -0.1778 0.2794)
						)
						(arc
							(start 0.1778 0.2794)
							(mid 0.249642 0.249642)
							(end 0.2794 0.1778)
						)
						(arc
							(start 0.2794 -0.1778)
							(mid 0.249642 -0.249642)
							(end 0.1778 -0.2794)
						)
					)
					(width 0)
					(fill yes)
				)
			)
		)
		(pad "2" smd custom
			(at 0 0.4445)
			(size 0.1397 0.1397)
			(layers "F.Cu" "F.Mask" "F.Paste")
			(net "ADC_P3V3")
			(options
				(clearance outline)
				(anchor circle)
			)
			(primitives
				(gr_poly
					(pts
						(arc
							(start -0.1778 -0.2794)
							(mid -0.249642 -0.249642)
							(end -0.2794 -0.1778)
						)
						(arc
							(start -0.2794 0.1778)
							(mid -0.249642 0.249642)
							(end -0.1778 0.2794)
						)
						(arc
							(start 0.1778 0.2794)
							(mid 0.249642 0.249642)
							(end 0.2794 0.1778)
						)
						(arc
							(start 0.2794 -0.1778)
							(mid 0.249642 -0.249642)
							(end 0.1778 -0.2794)
						)
					)
					(width 0)
					(fill yes)
				)
			)
		)
	)
	(footprint ""
		(layer "F.Cu")
		(at 79.155544 -168.225216 180)
		(property "Reference" "C244"
			(at 0 0 180)
			(layer "F.SilkS")
			(hide yes)
			(effects
				(font
					(size 1.27 1.27)
				)
			)
		)
		(property "Value" "SC10U6D3V5KX-4GP"
			(at -0.0762 -6.1214 180)
			(unlocked yes)
			(layer "F.Fab")
			(hide yes)
			(effects
				(font
					(size 1.016 1.016)
					(thickness 0.1524)
				)
			)
		)
		(property "Device Type" "C805H58"
			(at -0.0762 -8.1534 180)
			(unlocked yes)
			(layer "F.Fab")
			(hide yes)
			(effects
				(font
					(size 1.016 1.016)
					(thickness 0.1524)
				)
			)
		)
		(duplicate_pad_numbers_are_jumpers no)
		(fp_line
			(start 0.635 0)
			(end -0.635 0)
			(stroke
				(width 0.508)
				(type default)
			)
			(layer "F.SilkS")
		)
		(fp_rect
			(start -0.9652 1.778)
			(end 0.9652 -1.778)
			(stroke
				(width 0)
				(type default)
			)
			(fill no)
			(layer "F.CrtYd")
		)
		(fp_poly
			(pts
				(xy -0.9652 -1.778) (xy 0.9652 -1.778) (xy 0.9652 1.778) (xy -0.9652 1.778)
			)
			(stroke
				(width 0)
				(type default)
			)
			(fill no)
			(layer "F.Fab")
		)
		(pad "1" smd rect
			(at 0 -0.9652 180)
			(size 1.397 1.143)
			(layers "F.Cu" "F.Mask" "F.Paste")
			(net "P1V8_STBY")
		)
		(pad "2" smd rect
			(at 0 0.9652 180)
			(size 1.397 1.143)
			(layers "F.Cu" "F.Mask" "F.Paste")
			(net "GND")
		)
	)
)
